(kicad_pcb
	(version 20260206)
	(generator "pcbnew")
	(generator_version "10.0")
	(general
		(thickness 1.6)
		(legacy_teardrops no)
	)
	(paper "A4")
	(title_block
		(title "04192023_DAF0TMB3IC0_F0TG_MB_C_brd_V02_OCP.brd")
		(comment 1 "Grand Teton / footprints 1760-1765 of 8354")
	)
	(layers
		(0 "F.Cu" signal "TOP")
		(4 "In1.Cu" signal "GND")
		(6 "In2.Cu" signal "IN1")
		(8 "In3.Cu" signal "GND1")
		(10 "In4.Cu" signal "IN2")
		(12 "In5.Cu" signal "GND2")
		(14 "In6.Cu" signal "IN3")
		(16 "In7.Cu" signal "GND3")
		(18 "In8.Cu" signal "VCC")
		(20 "In9.Cu" signal "VCC1")
		(22 "In10.Cu" signal "GND4")
		(24 "In11.Cu" signal "IN4")
		(26 "In12.Cu" signal "GND5")
		(28 "In13.Cu" signal "IN5")
		(30 "In14.Cu" signal "GND6")
		(32 "In15.Cu" signal "IN6")
		(34 "In16.Cu" signal "GND7")
		(2 "B.Cu" signal "BOTTOM")
		(9 "F.Adhes" user "F.Adhesive")
		(11 "B.Adhes" user "B.Adhesive")
		(13 "F.Paste" user "Package Geometry/Pastemask Top")
		(15 "B.Paste" user "Package Geometry/Pastemask Bottom")
		(5 "F.SilkS" user "Ref Des/Silkscreen Top")
		(7 "B.SilkS" user "Ref Des/Silkscreen Bottom")
		(1 "F.Mask" user "Board Geometry/Soldermask Top")
		(3 "B.Mask" user "Board Geometry/Soldermask Bottom")
		(17 "Dwgs.User" user "User.Drawings")
		(19 "Cmts.User" user "User.Comments")
		(21 "Eco1.User" user "User.Eco1")
		(23 "Eco2.User" user "User.Eco2")
		(25 "Edge.Cuts" user "Board Geometry/Outline")
		(27 "Margin" user)
		(31 "F.CrtYd" user "Package Geometry/Place Bound Top")
		(29 "B.CrtYd" user "Package Geometry/Place Bound Bottom")
		(35 "F.Fab" user "Ref Des/Assembly Top")
		(33 "B.Fab" user "Ref Des/Assembly Bottom")
	)
	(footprint ""
		(layer "F.Cu")
		(at 359.952036 -340.315042)
		(property "Reference" "H44"
			(at -0.528574 -5.339334 0)
			(unlocked yes)
			(layer "F.SilkS")
			(effects
				(font
					(size 0.7874 0.5842)
					(thickness 0.1524)
				)
				(justify left)
			)
		)
		(property "Value" ""
			(at 0 0 0)
			(layer "F.Fab")
			(effects
				(font
					(size 1.27 1.27)
				)
			)
		)
		(duplicate_pad_numbers_are_jumpers no)
		(pad "1" thru_hole circle
			(at 0 0)
			(size 6.1976 6.1976)
			(drill 3.7338)
			(layers "*.Cu" "*.Mask")
			(remove_unused_layers no)
			(net "GND")
			(clearance -0.9779)
			(padstack
				(mode front_inner_back)
				(layer "Inner"
					(shape circle)
					(size 5.5372 5.5372)
					(clearance -0.6477)
				)
				(layer "B.Cu"
					(shape circle)
					(size 6.1976 6.1976)
					(clearance -0.9779)
				)
			)
		)
	)
	(footprint ""
		(layer "F.Cu")
		(at 163.250118 -432.04003 90)
		(property "Reference" "U175"
			(at -2.29743 5.584952 90)
			(unlocked yes)
			(layer "F.SilkS")
			(effects
				(font
					(size 0.7874 0.5842)
					(thickness 0.1524)
				)
				(justify left)
			)
		)
		(property "Value" ""
			(at 0 0 90)
			(layer "F.Fab")
			(effects
				(font
					(size 1.27 1.27)
				)
			)
		)
		(duplicate_pad_numbers_are_jumpers no)
		(fp_line
			(start 1.3716 -1.524)
			(end 1.3716 1.524)
			(stroke
				(width 0.1524)
				(type default)
			)
			(layer "F.SilkS")
		)
		(fp_line
			(start 0.508 -1.524)
			(end 1.3716 -1.524)
			(stroke
				(width 0.1524)
				(type default)
			)
			(layer "F.SilkS")
		)
		(fp_line
			(start -0.508 -1.524)
			(end 0 -1.016)
			(stroke
				(width 0.1524)
				(type default)
			)
			(layer "F.SilkS")
		)
		(fp_line
			(start -1.3716 -1.524)
			(end -0.508 -1.524)
			(stroke
				(width 0.1524)
				(type default)
			)
			(layer "F.SilkS")
		)
		(fp_line
			(start 0 -1.016)
			(end 0.508 -1.524)
			(stroke
				(width 0.1524)
				(type default)
			)
			(layer "F.SilkS")
		)
		(fp_line
			(start 1.3716 1.524)
			(end -1.3716 1.524)
			(stroke
				(width 0.1524)
				(type default)
			)
			(layer "F.SilkS")
		)
		(fp_line
			(start -1.3716 1.524)
			(end -1.3716 -1.524)
			(stroke
				(width 0.1524)
				(type default)
			)
			(layer "F.SilkS")
		)
		(fp_poly
			(pts
				(xy -3.60172 -0.719328) (xy -3.60172 -1.344168) (xy -3.048 -1.016)
			)
			(stroke
				(width 0)
				(type default)
			)
			(fill yes)
			(layer "F.SilkS")
		)
		(fp_line
			(start 1.5494 -1.524)
			(end 1.5494 -1.0668)
			(stroke
				(width 0.1)
				(type default)
			)
			(layer "F.Fab")
		)
		(fp_line
			(start -1.5494 -1.524)
			(end 1.5494 -1.524)
			(stroke
				(width 0.1)
				(type default)
			)
			(layer "F.Fab")
		)
		(fp_line
			(start 2.54 -1.0668)
			(end 2.54 1.0668)
			(stroke
				(width 0.1)
				(type default)
			)
			(layer "F.Fab")
		)
		(fp_line
			(start 1.5494 -1.0668)
			(end 2.54 -1.0668)
			(stroke
				(width 0.1)
				(type default)
			)
			(layer "F.Fab")
		)
		(fp_line
			(start 1.5494 -1.0668)
			(end 1.5494 1.0668)
			(stroke
				(width 0.1)
				(type default)
			)
			(layer "F.Fab")
		)
		(fp_line
			(start -1.5494 -1.0668)
			(end -1.5494 -1.524)
			(stroke
				(width 0.1)
				(type default)
			)
			(layer "F.Fab")
		)
		(fp_line
			(start -2.54 -1.0668)
			(end -1.5494 -1.0668)
			(stroke
				(width 0.1)
				(type default)
			)
			(layer "F.Fab")
		)
		(fp_line
			(start 2.54 1.0668)
			(end 1.5494 1.0668)
			(stroke
				(width 0.1)
				(type default)
			)
			(layer "F.Fab")
		)
		(fp_line
			(start 1.5494 1.0668)
			(end 1.5494 1.524)
			(stroke
				(width 0.1)
				(type default)
			)
			(layer "F.Fab")
		)
		(fp_line
			(start -1.5494 1.0668)
			(end -1.5494 -1.0668)
			(stroke
				(width 0.1)
				(type default)
			)
			(layer "F.Fab")
		)
		(fp_line
			(start -1.5494 1.0668)
			(end -2.54 1.0668)
			(stroke
				(width 0.1)
				(type default)
			)
			(layer "F.Fab")
		)
		(fp_line
			(start -2.54 1.0668)
			(end -2.54 -1.0668)
			(stroke
				(width 0.1)
				(type default)
			)
			(layer "F.Fab")
		)
		(fp_line
			(start 1.5494 1.524)
			(end -1.5494 1.524)
			(stroke
				(width 0.1)
				(type default)
			)
			(layer "F.Fab")
		)
		(fp_line
			(start -1.5494 1.524)
			(end -1.5494 1.0668)
			(stroke
				(width 0.1)
				(type default)
			)
			(layer "F.Fab")
		)
		(fp_poly
			(pts
				(xy -3.60172 -0.719328) (xy -3.60172 -1.344168) (xy -3.048 -1.016)
			)
			(stroke
				(width 0)
				(type default)
			)
			(fill yes)
			(layer "F.Fab")
		)
		(pad "1" smd rect
			(at -2.232406 -0.975106)
			(size 0.3556 1.4224)
			(layers "F.Cu" "F.Mask" "F.Paste")
			(net "SMB_BMC_SWB_EN_R")
		)
		(pad "2" smd rect
			(at -2.232406 -0.32512)
			(size 0.3556 1.4224)
			(layers "F.Cu" "F.Mask" "F.Paste")
			(net "SMB_BMC_SWB_BUF_R_SCL")
		)
		(pad "3" smd rect
			(at -2.232406 0.32512)
			(size 0.3556 1.4224)
			(layers "F.Cu" "F.Mask" "F.Paste")
			(net "SMB_BMC_SWB_R_SCL")
		)
		(pad "4" smd rect
			(at -2.232406 0.975106)
			(size 0.3556 1.4224)
			(layers "F.Cu" "F.Mask" "F.Paste")
			(net "GND")
		)
		(pad "5" smd rect
			(at 2.232406 0.975106)
			(size 0.3556 1.4224)
			(layers "F.Cu" "F.Mask" "F.Paste")
			(net "Net_10761")
		)
		(pad "6" smd rect
			(at 2.232406 0.32512)
			(size 0.3556 1.4224)
			(layers "F.Cu" "F.Mask" "F.Paste")
			(net "SMB_BMC_SWB_R_SDA")
		)
		(pad "7" smd rect
			(at 2.232406 -0.32512)
			(size 0.3556 1.4224)
			(layers "F.Cu" "F.Mask" "F.Paste")
			(net "SMB_BMC_SWB_BUF_R_SDA")
		)
		(pad "8" smd rect
			(at 2.232406 -0.975106)
			(size 0.3556 1.4224)
			(layers "F.Cu" "F.Mask" "F.Paste")
			(net "P3V3_AUX")
		)
	)
	(footprint ""
		(layer "F.Cu")
		(at 428.29353 -349.405956 90)
		(property "Reference" "PR389"
			(at 0 0 90)
			(layer "F.SilkS")
			(hide yes)
			(effects
				(font
					(size 1.27 1.27)
				)
			)
		)
		(property "Value" ""
			(at 0 0 90)
			(layer "F.Fab")
			(effects
				(font
					(size 1.27 1.27)
				)
			)
		)
		(duplicate_pad_numbers_are_jumpers no)
		(fp_line
			(start 0.7874 -0.4064)
			(end 0.7874 0.4064)
			(stroke
				(width 0.1524)
				(type default)
			)
			(layer "F.SilkS")
		)
		(fp_line
			(start -0.7874 -0.4064)
			(end 0.7874 -0.4064)
			(stroke
				(width 0.1524)
				(type default)
			)
			(layer "F.SilkS")
		)
		(fp_line
			(start 0.7874 0.4064)
			(end -0.7874 0.4064)
			(stroke
				(width 0.1524)
				(type default)
			)
			(layer "F.SilkS")
		)
		(fp_line
			(start -0.7874 0.4064)
			(end -0.7874 -0.4064)
			(stroke
				(width 0.1524)
				(type default)
			)
			(layer "F.SilkS")
		)
		(fp_line
			(start -0.12065 -0.305054)
			(end -0.12065 -0.2794)
			(stroke
				(width 0.1)
				(type default)
			)
			(layer "F.Fab")
		)
		(fp_line
			(start -0.67945 -0.305054)
			(end -0.12065 -0.305054)
			(stroke
				(width 0.1)
				(type default)
			)
			(layer "F.Fab")
		)
		(fp_line
			(start 0.67945 -0.3048)
			(end 0.67945 0.3048)
			(stroke
				(width 0.1)
				(type default)
			)
			(layer "F.Fab")
		)
		(fp_line
			(start 0.12065 -0.3048)
			(end 0.67945 -0.3048)
			(stroke
				(width 0.1)
				(type default)
			)
			(layer "F.Fab")
		)
		(fp_line
			(start 0.12065 -0.2794)
			(end 0.12065 -0.3048)
			(stroke
				(width 0.1)
				(type default)
			)
			(layer "F.Fab")
		)
		(fp_line
			(start -0.12065 -0.2794)
			(end 0.12065 -0.2794)
			(stroke
				(width 0.1)
				(type default)
			)
			(layer "F.Fab")
		)
		(fp_line
			(start 0.120396 0.2794)
			(end -0.12065 0.2794)
			(stroke
				(width 0.1)
				(type default)
			)
			(layer "F.Fab")
		)
		(fp_line
			(start -0.12065 0.2794)
			(end -0.12065 0.3048)
			(stroke
				(width 0.1)
				(type default)
			)
			(layer "F.Fab")
		)
		(fp_line
			(start 0.67945 0.3048)
			(end 0.120396 0.3048)
			(stroke
				(width 0.1)
				(type default)
			)
			(layer "F.Fab")
		)
		(fp_line
			(start 0.120396 0.3048)
			(end 0.120396 0.2794)
			(stroke
				(width 0.1)
				(type default)
			)
			(layer "F.Fab")
		)
		(fp_line
			(start -0.12065 0.3048)
			(end -0.67945 0.3048)
			(stroke
				(width 0.1)
				(type default)
			)
			(layer "F.Fab")
		)
		(fp_line
			(start -0.67945 0.3048)
			(end -0.67945 -0.305054)
			(stroke
				(width 0.1)
				(type default)
			)
			(layer "F.Fab")
		)
		(pad "1" smd circle
			(at -0.40005 0 90)
			(size 0 0)
			(layers "F.Cu" "F.Mask" "F.Paste")
			(net "SW_PVDD11_S3_P0_SW2_RC")
		)
		(pad "2" smd circle
			(at 0.40005 0 90)
			(size 0 0)
			(layers "F.Cu" "F.Mask" "F.Paste")
			(net "GND")
		)
	)
	(footprint ""
		(layer "F.Cu")
		(at 360.367072 -261.747762 -90)
		(property "Reference" "C2146"
			(at 0 0 270)
			(layer "F.SilkS")
			(hide yes)
			(effects
				(font
					(size 1.27 1.27)
				)
			)
		)
		(property "Value" ""
			(at 0 0 270)
			(layer "F.Fab")
			(effects
				(font
					(size 1.27 1.27)
				)
			)
		)
		(duplicate_pad_numbers_are_jumpers no)
		(fp_line
			(start -0.7874 0.4064)
			(end -0.7874 -0.4064)
			(stroke
				(width 0.1524)
				(type default)
			)
			(layer "F.SilkS")
		)
		(fp_line
			(start 0.7874 0.4064)
			(end -0.7874 0.4064)
			(stroke
				(width 0.1524)
				(type default)
			)
			(layer "F.SilkS")
		)
		(fp_line
			(start -0.7874 -0.4064)
			(end 0.7874 -0.4064)
			(stroke
				(width 0.1524)
				(type default)
			)
			(layer "F.SilkS")
		)
		(fp_line
			(start 0.7874 -0.4064)
			(end 0.7874 0.4064)
			(stroke
				(width 0.1524)
				(type default)
			)
			(layer "F.SilkS")
		)
		(fp_line
			(start -0.67945 0.3048)
			(end -0.67945 -0.305054)
			(stroke
				(width 0.1)
				(type default)
			)
			(layer "F.Fab")
		)
		(fp_line
			(start -0.12065 0.3048)
			(end -0.67945 0.3048)
			(stroke
				(width 0.1)
				(type default)
			)
			(layer "F.Fab")
		)
		(fp_line
			(start 0.120396 0.3048)
			(end 0.120396 0.2794)
			(stroke
				(width 0.1)
				(type default)
			)
			(layer "F.Fab")
		)
		(fp_line
			(start 0.67945 0.3048)
			(end 0.120396 0.3048)
			(stroke
				(width 0.1)
				(type default)
			)
			(layer "F.Fab")
		)
		(fp_line
			(start -0.12065 0.2794)
			(end -0.12065 0.3048)
			(stroke
				(width 0.1)
				(type default)
			)
			(layer "F.Fab")
		)
		(fp_line
			(start 0.120396 0.2794)
			(end -0.12065 0.2794)
			(stroke
				(width 0.1)
				(type default)
			)
			(layer "F.Fab")
		)
		(fp_line
			(start -0.12065 -0.2794)
			(end 0.12065 -0.2794)
			(stroke
				(width 0.1)
				(type default)
			)
			(layer "F.Fab")
		)
		(fp_line
			(start 0.12065 -0.2794)
			(end 0.12065 -0.3048)
			(stroke
				(width 0.1)
				(type default)
			)
			(layer "F.Fab")
		)
		(fp_line
			(start 0.12065 -0.3048)
			(end 0.67945 -0.3048)
			(stroke
				(width 0.1)
				(type default)
			)
			(layer "F.Fab")
		)
		(fp_line
			(start 0.67945 -0.3048)
			(end 0.67945 0.3048)
			(stroke
				(width 0.1)
				(type default)
			)
			(layer "F.Fab")
		)
		(fp_line
			(start -0.67945 -0.305054)
			(end -0.12065 -0.305054)
			(stroke
				(width 0.1)
				(type default)
			)
			(layer "F.Fab")
		)
		(fp_line
			(start -0.12065 -0.305054)
			(end -0.12065 -0.2794)
			(stroke
				(width 0.1)
				(type default)
			)
			(layer "F.Fab")
		)
		(pad "1" smd circle
			(at -0.40005 0 270)
			(size 0 0)
			(layers "F.Cu" "F.Mask" "F.Paste")
			(net "PVDD11_S3_P0")
		)
		(pad "2" smd circle
			(at 0.40005 0 270)
			(size 0 0)
			(layers "F.Cu" "F.Mask" "F.Paste")
			(net "GND")
		)
	)
	(footprint ""
		(layer "F.Cu")
		(at 252.961648 -57.209182)
		(property "Reference" "PR3952"
			(at 0 0 0)
			(layer "F.SilkS")
			(hide yes)
			(effects
				(font
					(size 1.27 1.27)
				)
			)
		)
		(property "Value" ""
			(at 0 0 0)
			(layer "F.Fab")
			(effects
				(font
					(size 1.27 1.27)
				)
			)
		)
		(duplicate_pad_numbers_are_jumpers no)
		(fp_line
			(start -0.7874 -0.4064)
			(end 0.7874 -0.4064)
			(stroke
				(width 0.1524)
				(type default)
			)
			(layer "F.SilkS")
		)
		(fp_line
			(start -0.7874 0.4064)
			(end -0.7874 -0.4064)
			(stroke
				(width 0.1524)
				(type default)
			)
			(layer "F.SilkS")
		)
		(fp_line
			(start 0.7874 -0.4064)
			(end 0.7874 0.4064)
			(stroke
				(width 0.1524)
				(type default)
			)
			(layer "F.SilkS")
		)
		(fp_line
			(start 0.7874 0.4064)
			(end -0.7874 0.4064)
			(stroke
				(width 0.1524)
				(type default)
			)
			(layer "F.SilkS")
		)
		(fp_line
			(start -0.67945 -0.305054)
			(end -0.12065 -0.305054)
			(stroke
				(width 0.1)
				(type default)
			)
			(layer "F.Fab")
		)
		(fp_line
			(start -0.67945 0.3048)
			(end -0.67945 -0.305054)
			(stroke
				(width 0.1)
				(type default)
			)
			(layer "F.Fab")
		)
		(fp_line
			(start -0.12065 -0.305054)
			(end -0.12065 -0.2794)
			(stroke
				(width 0.1)
				(type default)
			)
			(layer "F.Fab")
		)
		(fp_line
			(start -0.12065 -0.2794)
			(end 0.12065 -0.2794)
			(stroke
				(width 0.1)
				(type default)
			)
			(layer "F.Fab")
		)
		(fp_line
			(start -0.12065 0.2794)
			(end -0.12065 0.3048)
			(stroke
				(width 0.1)
				(type default)
			)
			(layer "F.Fab")
		)
		(fp_line
			(start -0.12065 0.3048)
			(end -0.67945 0.3048)
			(stroke
				(width 0.1)
				(type default)
			)
			(layer "F.Fab")
		)
		(fp_line
			(start 0.120396 0.2794)
			(end -0.12065 0.2794)
			(stroke
				(width 0.1)
				(type default)
			)
			(layer "F.Fab")
		)
		(fp_line
			(start 0.120396 0.3048)
			(end 0.120396 0.2794)
			(stroke
				(width 0.1)
				(type default)
			)
			(layer "F.Fab")
		)
		(fp_line
			(start 0.12065 -0.3048)
			(end 0.67945 -0.3048)
			(stroke
				(width 0.1)
				(type default)
			)
			(layer "F.Fab")
		)
		(fp_line
			(start 0.12065 -0.2794)
			(end 0.12065 -0.3048)
			(stroke
				(width 0.1)
				(type default)
			)
			(layer "F.Fab")
		)
		(fp_line
			(start 0.67945 -0.3048)
			(end 0.67945 0.3048)
			(stroke
				(width 0.1)
				(type default)
			)
			(layer "F.Fab")
		)
		(fp_line
			(start 0.67945 0.3048)
			(end 0.120396 0.3048)
			(stroke
				(width 0.1)
				(type default)
			)
			(layer "F.Fab")
		)
		(pad "1" smd circle
			(at -0.40005 0)
			(size 0 0)
			(layers "F.Cu" "F.Mask" "F.Paste")
			(net "P12V_E1S_0")
		)
		(pad "2" smd circle
			(at 0.40005 0)
			(size 0 0)
			(layers "F.Cu" "F.Mask" "F.Paste")
			(net "P12V_E1S_OV_FB_0")
		)
	)
	(footprint ""
		(layer "F.Cu")
		(at 172.593 -100.294948 -90)
		(property "Reference" "R6012"
			(at 0 0 270)
			(layer "F.SilkS")
			(hide yes)
			(effects
				(font
					(size 1.27 1.27)
				)
			)
		)
		(property "Value" ""
			(at 0 0 270)
			(layer "F.Fab")
			(effects
				(font
					(size 1.27 1.27)
				)
			)
		)
		(duplicate_pad_numbers_are_jumpers no)
		(fp_line
			(start -0.7874 0.4064)
			(end -0.7874 -0.4064)
			(stroke
				(width 0.1524)
				(type default)
			)
			(layer "F.SilkS")
		)
		(fp_line
			(start 0.7874 0.4064)
			(end -0.7874 0.4064)
			(stroke
				(width 0.1524)
				(type default)
			)
			(layer "F.SilkS")
		)
		(fp_line
			(start -0.7874 -0.4064)
			(end 0.7874 -0.4064)
			(stroke
				(width 0.1524)
				(type default)
			)
			(layer "F.SilkS")
		)
		(fp_line
			(start 0.7874 -0.4064)
			(end 0.7874 0.4064)
			(stroke
				(width 0.1524)
				(type default)
			)
			(layer "F.SilkS")
		)
		(fp_line
			(start -0.67945 0.3048)
			(end -0.67945 -0.305054)
			(stroke
				(width 0.1)
				(type default)
			)
			(layer "F.Fab")
		)
		(fp_line
			(start -0.12065 0.3048)
			(end -0.67945 0.3048)
			(stroke
				(width 0.1)
				(type default)
			)
			(layer "F.Fab")
		)
		(fp_line
			(start 0.120396 0.3048)
			(end 0.120396 0.2794)
			(stroke
				(width 0.1)
				(type default)
			)
			(layer "F.Fab")
		)
		(fp_line
			(start 0.67945 0.3048)
			(end 0.120396 0.3048)
			(stroke
				(width 0.1)
				(type default)
			)
			(layer "F.Fab")
		)
		(fp_line
			(start -0.12065 0.2794)
			(end -0.12065 0.3048)
			(stroke
				(width 0.1)
				(type default)
			)
			(layer "F.Fab")
		)
		(fp_line
			(start 0.120396 0.2794)
			(end -0.12065 0.2794)
			(stroke
				(width 0.1)
				(type default)
			)
			(layer "F.Fab")
		)
		(fp_line
			(start -0.12065 -0.2794)
			(end 0.12065 -0.2794)
			(stroke
				(width 0.1)
				(type default)
			)
			(layer "F.Fab")
		)
		(fp_line
			(start 0.12065 -0.2794)
			(end 0.12065 -0.3048)
			(stroke
				(width 0.1)
				(type default)
			)
			(layer "F.Fab")
		)
		(fp_line
			(start 0.12065 -0.3048)
			(end 0.67945 -0.3048)
			(stroke
				(width 0.1)
				(type default)
			)
			(layer "F.Fab")
		)
		(fp_line
			(start 0.67945 -0.3048)
			(end 0.67945 0.3048)
			(stroke
				(width 0.1)
				(type default)
			)
			(layer "F.Fab")
		)
		(fp_line
			(start -0.67945 -0.305054)
			(end -0.12065 -0.305054)
			(stroke
				(width 0.1)
				(type default)
			)
			(layer "F.Fab")
		)
		(fp_line
			(start -0.12065 -0.305054)
			(end -0.12065 -0.2794)
			(stroke
				(width 0.1)
				(type default)
			)
			(layer "F.Fab")
		)
		(pad "1" smd circle
			(at -0.40005 0 270)
			(size 0 0)
			(layers "F.Cu" "F.Mask" "F.Paste")
			(net "SGPIO_SCM_DO_<1>")
		)
		(pad "2" smd circle
			(at 0.40005 0 270)
			(size 0 0)
			(layers "F.Cu" "F.Mask" "F.Paste")
			(net "SGPIO_SCM_DO_R_<1>")
		)
	)
)
